(kicad_pcb
	(version 20260206)
	(generator "pcbnew")
	(generator_version "10.0")
	(general
		(thickness 1.6)
		(legacy_teardrops no)
	)
	(paper "A4")
	(title_block
		(title "03242023_DA0F0TMBIJ0_F0T_Motherboard_J_brd_V01_OCP.brd")
		(comment 1 "Grand Teton / footprint 1682 of 6105 (U1), pads 3135-3245 of 4677")
	)
	(layers
		(0 "F.Cu" signal "TOP")
		(4 "In1.Cu" signal "GND")
		(6 "In2.Cu" signal "IN1")
		(8 "In3.Cu" signal "GND1")
		(10 "In4.Cu" signal "IN2")
		(12 "In5.Cu" signal "GND2")
		(14 "In6.Cu" signal "IN3")
		(16 "In7.Cu" signal "GND3")
		(18 "In8.Cu" signal "VCC")
		(20 "In9.Cu" signal "VCC1")
		(22 "In10.Cu" signal "GND4")
		(24 "In11.Cu" signal "IN4")
		(26 "In12.Cu" signal "GND5")
		(28 "In13.Cu" signal "IN5")
		(30 "In14.Cu" signal "GND6")
		(32 "In15.Cu" signal "IN6")
		(34 "In16.Cu" signal "GND7")
		(2 "B.Cu" signal "BOTTOM")
		(9 "F.Adhes" user "F.Adhesive")
		(11 "B.Adhes" user "B.Adhesive")
		(13 "F.Paste" user "Package Geometry/Pastemask Top")
		(15 "B.Paste" user "Package Geometry/Pastemask Bottom")
		(5 "F.SilkS" user "Ref Des/Silkscreen Top")
		(7 "B.SilkS" user "Ref Des/Silkscreen Bottom")
		(1 "F.Mask" user "Board Geometry/Soldermask Top")
		(3 "B.Mask" user "Board Geometry/Soldermask Bottom")
		(17 "Dwgs.User" user "User.Drawings")
		(19 "Cmts.User" user "User.Comments")
		(21 "Eco1.User" user "User.Eco1")
		(23 "Eco2.User" user "User.Eco2")
		(25 "Edge.Cuts" user "Board Geometry/Outline")
		(27 "Margin" user)
		(31 "F.CrtYd" user "Package Geometry/Place Bound Top")
		(29 "B.CrtYd" user "Package Geometry/Place Bound Bottom")
		(35 "F.Fab" user "Ref Des/Assembly Top")
		(33 "B.Fab" user "Ref Des/Assembly Bottom")
	)
	(footprint ""
		(layer "F.Cu")
		(at 111.93018 -251.76988 90)
		(property "Reference" "U1"
			(at -74.913236 41.548812 0)
			(unlocked yes)
			(layer "F.SilkS")
			(effects
				(font
					(size 1.6002 1.1938)
					(thickness 0.1524)
				)
				(justify left)
			)
		)
		(property "Value" ""
			(at 0 0 90)
			(layer "F.Fab")
			(effects
				(font
					(size 1.27 1.27)
				)
			)
		)
		(duplicate_pad_numbers_are_jumpers no)
		(pad "DU50" smd circle
			(at 4.055618 18.146268 270)
			(size 0.4318 0.4318)
			(layers "F.Cu" "F.Mask" "F.Paste")
			(net "M_F_CPU1_SB_CA<1>")
		)
		(pad "DU52" smd circle
			(at 5.68325 18.146268 270)
			(size 0.4318 0.4318)
			(layers "F.Cu" "F.Mask" "F.Paste")
			(net "GND")
		)
		(pad "DU54" smd circle
			(at 7.311136 18.146268 270)
			(size 0.4318 0.4318)
			(layers "F.Cu" "F.Mask" "F.Paste")
			(net "M_F_CPU1_SA_DQ<28>")
		)
		(pad "DU56" smd circle
			(at 8.939022 18.146268 270)
			(size 0.4318 0.4318)
			(layers "F.Cu" "F.Mask" "F.Paste")
			(net "M_F_CPU1_SA_DQ<25>")
		)
		(pad "DU58" smd circle
			(at 10.566654 18.146268 270)
			(size 0.4318 0.4318)
			(layers "F.Cu" "F.Mask" "F.Paste")
			(net "GND")
		)
		(pad "DU60" smd circle
			(at 12.19454 18.146268 270)
			(size 0.4318 0.4318)
			(layers "F.Cu" "F.Mask" "F.Paste")
			(net "M_G_CPU1_SA_DQ<20>")
		)
		(pad "DU62" smd circle
			(at 13.822426 18.146268 270)
			(size 0.4318 0.4318)
			(layers "F.Cu" "F.Mask" "F.Paste")
			(net "M_G_CPU1_SA_DQ<17>")
		)
		(pad "DU64" smd circle
			(at 15.450058 18.146268 270)
			(size 0.4318 0.4318)
			(layers "F.Cu" "F.Mask" "F.Paste")
			(net "GND")
		)
		(pad "DU66" smd circle
			(at 17.07769 18.146268 270)
			(size 0.4318 0.4318)
			(layers "F.Cu" "F.Mask" "F.Paste")
			(net "M_F_CPU1_SA_DQ<12>")
		)
		(pad "DU68" smd circle
			(at 18.705576 18.146268 270)
			(size 0.4318 0.4318)
			(layers "F.Cu" "F.Mask" "F.Paste")
			(net "M_F_CPU1_SA_DQ<9>")
		)
		(pad "DU70" smd circle
			(at 20.333462 18.146268 270)
			(size 0.4318 0.4318)
			(layers "F.Cu" "F.Mask" "F.Paste")
			(net "GND")
		)
		(pad "DU72" smd circle
			(at 21.961094 18.146268 270)
			(size 0.4318 0.4318)
			(layers "F.Cu" "F.Mask" "F.Paste")
			(net "M_G_CPU1_SA_DQ<4>")
		)
		(pad "DU74" smd circle
			(at 23.58898 18.146268 270)
			(size 0.4318 0.4318)
			(layers "F.Cu" "F.Mask" "F.Paste")
			(net "M_G_CPU1_SA_DQ<1>")
		)
		(pad "DU76" smd circle
			(at 25.216612 18.146268 270)
			(size 0.4318 0.4318)
			(layers "F.Cu" "F.Mask" "F.Paste")
			(net "GND")
		)
		(pad "DU78" smd circle
			(at 26.844498 18.146268 270)
			(size 0.4318 0.4318)
			(layers "F.Cu" "F.Mask" "F.Paste")
			(net "GND")
		)
		(pad "DU80" smd circle
			(at 28.472384 18.146268 270)
			(size 0.4318 0.4318)
			(layers "F.Cu" "F.Mask" "F.Paste")
			(net "Net_729")
		)
		(pad "DU82" smd circle
			(at 30.100016 18.146268 270)
			(size 0.4318 0.4318)
			(layers "F.Cu" "F.Mask" "F.Paste")
			(net "Net_704")
		)
		(pad "DU84" smd circle
			(at 31.727902 18.146268 270)
			(size 0.4318 0.4318)
			(layers "F.Cu" "F.Mask" "F.Paste")
			(net "GND")
		)
		(pad "DU86" smd circle
			(at 33.355534 18.146268 270)
			(size 0.4318 0.4318)
			(layers "F.Cu" "F.Mask" "F.Paste")
			(net "P5E_CPU1_PE3_TX_DP<4>")
		)
		(pad "DU88" smd circle
			(at 34.98342 18.146268 270)
			(size 0.4318 0.4318)
			(layers "F.Cu" "F.Mask" "F.Paste")
			(net "GND")
		)
		(pad "DU90" smd circle
			(at 36.611306 18.146268 270)
			(size 0.4318 0.4318)
			(layers "F.Cu" "F.Mask" "F.Paste")
			(net "P5E_CPU1_PE3_RX_DN<5>")
		)
		(pad "DV2" smd circle
			(at -36.611306 18.505932 270)
			(size 0.4318 0.4318)
			(layers "F.Cu" "F.Mask" "F.Paste")
			(net "UPI_CPU0_CPU1_P0P1_DP<5>")
		)
		(pad "DV4" smd circle
			(at -34.98342 18.505932 270)
			(size 0.4318 0.4318)
			(layers "F.Cu" "F.Mask" "F.Paste")
			(net "GND")
		)
		(pad "DV6" smd circle
			(at -33.355534 18.505932 270)
			(size 0.4318 0.4318)
			(layers "F.Cu" "F.Mask" "F.Paste")
			(net "UPI_CPU1_CPU0_P1P0_DN<4>")
		)
		(pad "DV8" smd circle
			(at -31.727902 18.505932 270)
			(size 0.4318 0.4318)
			(layers "F.Cu" "F.Mask" "F.Paste")
			(net "GND")
		)
		(pad "DV10" smd circle
			(at -30.100016 18.505932 270)
			(size 0.4318 0.4318)
			(layers "F.Cu" "F.Mask" "F.Paste")
			(net "P5E_CPU1_PE2_RX_DP<10>")
		)
		(pad "DV12" smd circle
			(at -28.472384 18.505932 270)
			(size 0.4318 0.4318)
			(layers "F.Cu" "F.Mask" "F.Paste")
			(net "GND")
		)
		(pad "DV14" smd circle
			(at -26.844498 18.505932 270)
			(size 0.4318 0.4318)
			(layers "F.Cu" "F.Mask" "F.Paste")
			(net "P5E_CPU1_PE2_TX_DN<11>")
		)
		(pad "DV16" smd circle
			(at -25.216612 18.505932 270)
			(size 0.4318 0.4318)
			(layers "F.Cu" "F.Mask" "F.Paste")
			(net "GND")
		)
		(pad "DV18" smd circle
			(at -23.58898 18.505932 270)
			(size 0.4318 0.4318)
			(layers "F.Cu" "F.Mask" "F.Paste")
			(net "M_F_CPU1_SB_DQS_DP<3>")
		)
		(pad "DV20" smd circle
			(at -21.961094 18.505932 270)
			(size 0.4318 0.4318)
			(layers "F.Cu" "F.Mask" "F.Paste")
			(net "M_F_CPU1_SB_DQ<24>")
		)
		(pad "DV22" smd circle
			(at -20.333462 18.505932 270)
			(size 0.4318 0.4318)
			(layers "F.Cu" "F.Mask" "F.Paste")
			(net "M_G_CPU1_SB_DQ<21>")
		)
		(pad "DV24" smd circle
			(at -18.705576 18.505932 270)
			(size 0.4318 0.4318)
			(layers "F.Cu" "F.Mask" "F.Paste")
			(net "M_G_CPU1_SB_DQS_DN<2>")
		)
		(pad "DV26" smd circle
			(at -17.07769 18.505932 270)
			(size 0.4318 0.4318)
			(layers "F.Cu" "F.Mask" "F.Paste")
			(net "M_G_CPU1_SB_DQ<16>")
		)
		(pad "DV28" smd circle
			(at -15.450058 18.505932 270)
			(size 0.4318 0.4318)
			(layers "F.Cu" "F.Mask" "F.Paste")
			(net "M_F_CPU1_SB_DQ<5>")
		)
		(pad "DV30" smd circle
			(at -13.822426 18.505932 270)
			(size 0.4318 0.4318)
			(layers "F.Cu" "F.Mask" "F.Paste")
			(net "M_F_CPU1_SB_DQS_DN<0>")
		)
		(pad "DV32" smd circle
			(at -12.19454 18.505932 270)
			(size 0.4318 0.4318)
			(layers "F.Cu" "F.Mask" "F.Paste")
			(net "M_F_CPU1_SB_DQ<0>")
		)
		(pad "DV34" smd circle
			(at -10.566654 18.505932 270)
			(size 0.4318 0.4318)
			(layers "F.Cu" "F.Mask" "F.Paste")
			(net "M_G_CPU1_SB_CB<1>")
		)
		(pad "DV36" smd circle
			(at -8.939022 18.505932 270)
			(size 0.4318 0.4318)
			(layers "F.Cu" "F.Mask" "F.Paste")
			(net "M_G_CPU1_SB_DQS_DN<9>")
		)
		(pad "DV38" smd circle
			(at -7.311136 18.505932 270)
			(size 0.4318 0.4318)
			(layers "F.Cu" "F.Mask" "F.Paste")
			(net "M_G_CPU1_SB_CB<4>")
		)
		(pad "DV40" smd circle
			(at -5.68325 18.505932 270)
			(size 0.4318 0.4318)
			(layers "F.Cu" "F.Mask" "F.Paste")
			(net "M_G_CPU1_SB_CS_N<3>")
		)
		(pad "DV42" smd circle
			(at -4.055618 18.505932 270)
			(size 0.4318 0.4318)
			(layers "F.Cu" "F.Mask" "F.Paste")
			(net "GND")
		)
		(pad "DV44" smd circle
			(at -2.427732 18.505932 270)
			(size 0.4318 0.4318)
			(layers "F.Cu" "F.Mask" "F.Paste")
			(net "M_G_CPU1_SB_CA<2>")
		)
		(pad "DV47" smd circle
			(at 1.613916 18.615914 270)
			(size 0.4318 0.4318)
			(layers "F.Cu" "F.Mask" "F.Paste")
			(net "M_G_CPU1_SB_RSP<1>")
		)
		(pad "DV49" smd circle
			(at 3.241802 18.615914 270)
			(size 0.4318 0.4318)
			(layers "F.Cu" "F.Mask" "F.Paste")
			(net "M_F_CPU1_CLK_DN<1>")
		)
		(pad "DV51" smd circle
			(at 4.869434 18.615914 270)
			(size 0.4318 0.4318)
			(layers "F.Cu" "F.Mask" "F.Paste")
			(net "M_F_CPU1_SB_CA<0>")
		)
		(pad "DV53" smd circle
			(at 6.49732 18.615914 270)
			(size 0.4318 0.4318)
			(layers "F.Cu" "F.Mask" "F.Paste")
			(net "M_F_CPU1_SA_DQ<29>")
		)
		(pad "DV55" smd circle
			(at 8.124952 18.615914 270)
			(size 0.4318 0.4318)
			(layers "F.Cu" "F.Mask" "F.Paste")
			(net "M_F_CPU1_SA_DQS_DN<3>")
		)
		(pad "DV57" smd circle
			(at 9.752838 18.615914 270)
			(size 0.4318 0.4318)
			(layers "F.Cu" "F.Mask" "F.Paste")
			(net "M_F_CPU1_SA_DQ<24>")
		)
		(pad "DV59" smd circle
			(at 11.380724 18.615914 270)
			(size 0.4318 0.4318)
			(layers "F.Cu" "F.Mask" "F.Paste")
			(net "M_G_CPU1_SA_DQ<21>")
		)
		(pad "DV61" smd circle
			(at 13.008356 18.615914 270)
			(size 0.4318 0.4318)
			(layers "F.Cu" "F.Mask" "F.Paste")
			(net "M_G_CPU1_SA_DQS_DP<2>")
		)
		(pad "DV63" smd circle
			(at 14.635988 18.615914 270)
			(size 0.4318 0.4318)
			(layers "F.Cu" "F.Mask" "F.Paste")
			(net "M_G_CPU1_SA_DQ<16>")
		)
		(pad "DV65" smd circle
			(at 16.263874 18.615914 270)
			(size 0.4318 0.4318)
			(layers "F.Cu" "F.Mask" "F.Paste")
			(net "M_F_CPU1_SA_DQ<13>")
		)
		(pad "DV67" smd circle
			(at 17.89176 18.615914 270)
			(size 0.4318 0.4318)
			(layers "F.Cu" "F.Mask" "F.Paste")
			(net "M_F_CPU1_SA_DQS_DP<1>")
		)
		(pad "DV69" smd circle
			(at 19.519392 18.615914 270)
			(size 0.4318 0.4318)
			(layers "F.Cu" "F.Mask" "F.Paste")
			(net "M_F_CPU1_SA_DQ<8>")
		)
		(pad "DV71" smd circle
			(at 21.147278 18.615914 270)
			(size 0.4318 0.4318)
			(layers "F.Cu" "F.Mask" "F.Paste")
			(net "M_G_CPU1_SA_DQ<5>")
		)
		(pad "DV73" smd circle
			(at 22.77491 18.615914 270)
			(size 0.4318 0.4318)
			(layers "F.Cu" "F.Mask" "F.Paste")
			(net "M_G_CPU1_SA_DQS_DN<0>")
		)
		(pad "DV75" smd circle
			(at 24.402796 18.615914 270)
			(size 0.4318 0.4318)
			(layers "F.Cu" "F.Mask" "F.Paste")
			(net "M_G_CPU1_SA_DQ<0>")
		)
		(pad "DV77" smd circle
			(at 26.030682 18.615914 270)
			(size 0.4318 0.4318)
			(layers "F.Cu" "F.Mask" "F.Paste")
			(net "GND")
		)
		(pad "DV79" smd circle
			(at 27.658314 18.615914 270)
			(size 0.4318 0.4318)
			(layers "F.Cu" "F.Mask" "F.Paste")
			(net "GND")
		)
		(pad "DV81" smd circle
			(at 29.2862 18.615914 270)
			(size 0.4318 0.4318)
			(layers "F.Cu" "F.Mask" "F.Paste")
			(net "GND")
		)
		(pad "DV83" smd circle
			(at 30.914086 18.615914 270)
			(size 0.4318 0.4318)
			(layers "F.Cu" "F.Mask" "F.Paste")
			(net "GND")
		)
		(pad "DV85" smd circle
			(at 32.541718 18.615914 270)
			(size 0.4318 0.4318)
			(layers "F.Cu" "F.Mask" "F.Paste")
			(net "P5E_CPU1_PE3_TX_DN<3>")
		)
		(pad "DV87" smd circle
			(at 34.169604 18.615914 270)
			(size 0.4318 0.4318)
			(layers "F.Cu" "F.Mask" "F.Paste")
			(net "GND")
		)
		(pad "DV89" smd circle
			(at 35.797236 18.615914 270)
			(size 0.4318 0.4318)
			(layers "F.Cu" "F.Mask" "F.Paste")
			(net "P5E_CPU1_PE3_RX_DN<4>")
		)
		(pad "DV91" smd oval
			(at 37.425122 18.615914)
			(size 0.381 0.4826)
			(drill
				(offset 0 -0.0508)
			)
			(layers "F.Cu" "F.Mask" "F.Paste")
			(net "GND")
		)
		(pad "DW1" smd oval
			(at -37.425122 18.976086 180)
			(size 0.381 0.4826)
			(drill
				(offset 0 -0.0508)
			)
			(layers "F.Cu" "F.Mask" "F.Paste")
			(net "GND")
		)
		(pad "DW3" smd circle
			(at -35.797236 18.976086 270)
			(size 0.4318 0.4318)
			(layers "F.Cu" "F.Mask" "F.Paste")
			(net "UPI_CPU0_CPU1_P0P1_DP<4>")
		)
		(pad "DW5" smd circle
			(at -34.169604 18.976086 270)
			(size 0.4318 0.4318)
			(layers "F.Cu" "F.Mask" "F.Paste")
			(net "GND")
		)
		(pad "DW7" smd circle
			(at -32.541718 18.976086 270)
			(size 0.4318 0.4318)
			(layers "F.Cu" "F.Mask" "F.Paste")
			(net "UPI_CPU1_CPU0_P1P0_DP<3>")
		)
		(pad "DW9" smd circle
			(at -30.914086 18.976086 270)
			(size 0.4318 0.4318)
			(layers "F.Cu" "F.Mask" "F.Paste")
			(net "GND")
		)
		(pad "DW11" smd circle
			(at -29.2862 18.976086 270)
			(size 0.4318 0.4318)
			(layers "F.Cu" "F.Mask" "F.Paste")
			(net "P5E_CPU1_PE2_RX_DP<11>")
		)
		(pad "DW13" smd circle
			(at -27.658314 18.976086 270)
			(size 0.4318 0.4318)
			(layers "F.Cu" "F.Mask" "F.Paste")
			(net "GND")
		)
		(pad "DW15" smd circle
			(at -26.030682 18.976086 270)
			(size 0.4318 0.4318)
			(layers "F.Cu" "F.Mask" "F.Paste")
			(net "P5E_CPU1_PE2_TX_DP<11>")
		)
		(pad "DW17" smd circle
			(at -24.402796 18.976086 270)
			(size 0.4318 0.4318)
			(layers "F.Cu" "F.Mask" "F.Paste")
			(net "GND")
		)
		(pad "DW19" smd circle
			(at -22.77491 18.976086 270)
			(size 0.4318 0.4318)
			(layers "F.Cu" "F.Mask" "F.Paste")
			(net "GND")
		)
		(pad "DW21" smd circle
			(at -21.147278 18.976086 270)
			(size 0.4318 0.4318)
			(layers "F.Cu" "F.Mask" "F.Paste")
			(net "GND")
		)
		(pad "DW23" smd circle
			(at -19.519392 18.976086 270)
			(size 0.4318 0.4318)
			(layers "F.Cu" "F.Mask" "F.Paste")
			(net "GND")
		)
		(pad "DW25" smd circle
			(at -17.89176 18.976086 270)
			(size 0.4318 0.4318)
			(layers "F.Cu" "F.Mask" "F.Paste")
			(net "GND")
		)
		(pad "DW27" smd circle
			(at -16.263874 18.976086 270)
			(size 0.4318 0.4318)
			(layers "F.Cu" "F.Mask" "F.Paste")
			(net "GND")
		)
		(pad "DW29" smd circle
			(at -14.635988 18.976086 270)
			(size 0.4318 0.4318)
			(layers "F.Cu" "F.Mask" "F.Paste")
			(net "GND")
		)
		(pad "DW31" smd circle
			(at -13.008356 18.976086 270)
			(size 0.4318 0.4318)
			(layers "F.Cu" "F.Mask" "F.Paste")
			(net "GND")
		)
		(pad "DW33" smd circle
			(at -11.380724 18.976086 270)
			(size 0.4318 0.4318)
			(layers "F.Cu" "F.Mask" "F.Paste")
			(net "GND")
		)
		(pad "DW35" smd circle
			(at -9.752838 18.976086 270)
			(size 0.4318 0.4318)
			(layers "F.Cu" "F.Mask" "F.Paste")
			(net "GND")
		)
		(pad "DW37" smd circle
			(at -8.124952 18.976086 270)
			(size 0.4318 0.4318)
			(layers "F.Cu" "F.Mask" "F.Paste")
			(net "GND")
		)
		(pad "DW39" smd circle
			(at -6.49732 18.976086 270)
			(size 0.4318 0.4318)
			(layers "F.Cu" "F.Mask" "F.Paste")
			(net "GND")
		)
		(pad "DW41" smd circle
			(at -4.869434 18.976086 270)
			(size 0.4318 0.4318)
			(layers "F.Cu" "F.Mask" "F.Paste")
			(net "GND")
		)
		(pad "DW43" smd circle
			(at -3.241802 18.976086 270)
			(size 0.4318 0.4318)
			(layers "F.Cu" "F.Mask" "F.Paste")
			(net "GND")
		)
		(pad "DW45" smd circle
			(at -1.613916 18.976086 270)
			(size 0.4318 0.4318)
			(layers "F.Cu" "F.Mask" "F.Paste")
			(net "GND")
		)
		(pad "DW48" smd circle
			(at 2.427732 19.086068 270)
			(size 0.4318 0.4318)
			(layers "F.Cu" "F.Mask" "F.Paste")
			(net "GND")
		)
		(pad "DW50" smd circle
			(at 4.055618 19.086068 270)
			(size 0.4318 0.4318)
			(layers "F.Cu" "F.Mask" "F.Paste")
			(net "GND")
		)
		(pad "DW52" smd circle
			(at 5.68325 19.086068 270)
			(size 0.4318 0.4318)
			(layers "F.Cu" "F.Mask" "F.Paste")
			(net "GND")
		)
		(pad "DW54" smd circle
			(at 7.311136 19.086068 270)
			(size 0.4318 0.4318)
			(layers "F.Cu" "F.Mask" "F.Paste")
			(net "GND")
		)
		(pad "DW56" smd circle
			(at 8.939022 19.086068 270)
			(size 0.4318 0.4318)
			(layers "F.Cu" "F.Mask" "F.Paste")
			(net "GND")
		)
		(pad "DW58" smd circle
			(at 10.566654 19.086068 270)
			(size 0.4318 0.4318)
			(layers "F.Cu" "F.Mask" "F.Paste")
			(net "GND")
		)
		(pad "DW60" smd circle
			(at 12.19454 19.086068 270)
			(size 0.4318 0.4318)
			(layers "F.Cu" "F.Mask" "F.Paste")
			(net "GND")
		)
		(pad "DW62" smd circle
			(at 13.822426 19.086068 270)
			(size 0.4318 0.4318)
			(layers "F.Cu" "F.Mask" "F.Paste")
			(net "GND")
		)
		(pad "DW64" smd circle
			(at 15.450058 19.086068 270)
			(size 0.4318 0.4318)
			(layers "F.Cu" "F.Mask" "F.Paste")
			(net "GND")
		)
		(pad "DW66" smd circle
			(at 17.07769 19.086068 270)
			(size 0.4318 0.4318)
			(layers "F.Cu" "F.Mask" "F.Paste")
			(net "GND")
		)
		(pad "DW68" smd circle
			(at 18.705576 19.086068 270)
			(size 0.4318 0.4318)
			(layers "F.Cu" "F.Mask" "F.Paste")
			(net "GND")
		)
		(pad "DW70" smd circle
			(at 20.333462 19.086068 270)
			(size 0.4318 0.4318)
			(layers "F.Cu" "F.Mask" "F.Paste")
			(net "GND")
		)
		(pad "DW72" smd circle
			(at 21.961094 19.086068 270)
			(size 0.4318 0.4318)
			(layers "F.Cu" "F.Mask" "F.Paste")
			(net "GND")
		)
		(pad "DW74" smd circle
			(at 23.58898 19.086068 270)
			(size 0.4318 0.4318)
			(layers "F.Cu" "F.Mask" "F.Paste")
			(net "GND")
		)
		(pad "DW76" smd circle
			(at 25.216612 19.086068 270)
			(size 0.4318 0.4318)
			(layers "F.Cu" "F.Mask" "F.Paste")
			(net "GND")
		)
		(pad "DW78" smd circle
			(at 26.844498 19.086068 270)
			(size 0.4318 0.4318)
			(layers "F.Cu" "F.Mask" "F.Paste")
			(net "M_H_CPU1_SA_DQ<2>")
		)
		(pad "DW80" smd circle
			(at 28.472384 19.086068 270)
			(size 0.4318 0.4318)
			(layers "F.Cu" "F.Mask" "F.Paste")
			(net "GND")
		)
		(pad "DW82" smd circle
			(at 30.100016 19.086068 270)
			(size 0.4318 0.4318)
			(layers "F.Cu" "F.Mask" "F.Paste")
			(net "GND")
		)
		(pad "DW84" smd circle
			(at 31.727902 19.086068 270)
			(size 0.4318 0.4318)
			(layers "F.Cu" "F.Mask" "F.Paste")
			(net "GND")
		)
		(pad "DW86" smd circle
			(at 33.355534 19.086068 270)
			(size 0.4318 0.4318)
			(layers "F.Cu" "F.Mask" "F.Paste")
			(net "P5E_CPU1_PE3_TX_DP<3>")
		)
		(pad "DW88" smd circle
			(at 34.98342 19.086068 270)
			(size 0.4318 0.4318)
			(layers "F.Cu" "F.Mask" "F.Paste")
			(net "GND")
		)
		(pad "DW90" smd circle
			(at 36.611306 19.086068 270)
			(size 0.4318 0.4318)
			(layers "F.Cu" "F.Mask" "F.Paste")
			(net "P5E_CPU1_PE3_RX_DP<4>")
		)
	)
)
